# S9S_MB_2U (Grand Teton) — schematic netlist excerpt (pin names and nets, part order shuffled) for the footprints in the layout excerpt that follows; sources: Cadence DE-HDL packaged netlist, KiCad conversion of 03242023_DA0F0TMBIJ0_F0T_Motherboard_J_brd_V01_OCP.brd

R4264  Q_RES  4.7K 5% CHIP  pkg 0402LF  page 246 : A = P3V3_AUX ; B = PWRGD_P3V3_AUX_PDB_BUF_R

X20  TP_TDR_4P_FTS  TP_TDR_4P_DIP EMPTY  pkg TH  page 309
  S1  = TDR_DIFF_100_IN1_DN
  P1  = T1_GND
  P2  = T1_GND
  S2  = TDR_DIFF_100_IN1_DP

(kicad_pcb
	(version 20260206)
	(generator "pcbnew")
	(generator_version "10.0")
	(general
		(thickness 1.6)
		(legacy_teardrops no)
	)
	(paper "A4")
	(title_block
		(title "03242023_DA0F0TMBIJ0_F0T_Motherboard_J_brd_V01_OCP.brd")
		(comment 1 "Grand Teton / footprints 65-66 of 6105")
	)
	(layers
		(0 "F.Cu" signal "TOP")
		(4 "In1.Cu" signal "GND")
		(6 "In2.Cu" signal "IN1")
		(8 "In3.Cu" signal "GND1")
		(10 "In4.Cu" signal "IN2")
		(12 "In5.Cu" signal "GND2")
		(14 "In6.Cu" signal "IN3")
		(16 "In7.Cu" signal "GND3")
		(18 "In8.Cu" signal "VCC")
		(20 "In9.Cu" signal "VCC1")
		(22 "In10.Cu" signal "GND4")
		(24 "In11.Cu" signal "IN4")
		(26 "In12.Cu" signal "GND5")
		(28 "In13.Cu" signal "IN5")
		(30 "In14.Cu" signal "GND6")
		(32 "In15.Cu" signal "IN6")
		(34 "In16.Cu" signal "GND7")
		(2 "B.Cu" signal "BOTTOM")
		(9 "F.Adhes" user "F.Adhesive")
		(11 "B.Adhes" user "B.Adhesive")
		(13 "F.Paste" user "Package Geometry/Pastemask Top")
		(15 "B.Paste" user "Package Geometry/Pastemask Bottom")
		(5 "F.SilkS" user "Ref Des/Silkscreen Top")
		(7 "B.SilkS" user "Ref Des/Silkscreen Bottom")
		(1 "F.Mask" user "Board Geometry/Soldermask Top")
		(3 "B.Mask" user "Board Geometry/Soldermask Bottom")
		(17 "Dwgs.User" user "User.Drawings")
		(19 "Cmts.User" user "User.Comments")
		(21 "Eco1.User" user "User.Eco1")
		(23 "Eco2.User" user "User.Eco2")
		(25 "Edge.Cuts" user "Board Geometry/Outline")
		(27 "Margin" user)
		(31 "F.CrtYd" user "Package Geometry/Place Bound Top")
		(29 "B.CrtYd" user "Package Geometry/Place Bound Bottom")
		(35 "F.Fab" user "Ref Des/Assembly Top")
		(33 "B.Fab" user "Ref Des/Assembly Bottom")
	)
	(footprint ""
		(layer "F.Cu")
		(at 511.924808 2.33172 -90)
		(property "Reference" "X20"
			(at -1.281684 3.260598 90)
			(unlocked yes)
			(layer "F.SilkS")
			(effects
				(font
					(size 0.7874 0.5842)
					(thickness 0.1524)
				)
				(justify left)
			)
		)
		(property "Value" ""
			(at 0 0 270)
			(layer "F.Fab")
			(effects
				(font
					(size 1.27 1.27)
				)
			)
		)
		(property "Device Type" "TP_TDR_4P_FTS_MPKT4_H025P0200_I"
			(at 1.30175 1.27 0)
			(unlocked yes)
			(layer "F.Fab")
			(hide yes)
			(effects
				(font
					(size 0.635 0.4064)
					(thickness 0.1524)
				)
			)
		)
		(property "User Part Number" "TP15"
			(at 1.30175 1.27 0)
			(unlocked yes)
			(layer "Cmts.User")
			(hide yes)
			(effects
				(font
					(size 0.635 0.4064)
					(thickness 0.1524)
				)
			)
		)
		(duplicate_pad_numbers_are_jumpers no)
		(fp_line
			(start 0 3.81)
			(end 2.54 3.81)
			(stroke
				(width 0.1524)
				(type default)
			)
			(layer "F.SilkS")
		)
		(fp_line
			(start 2.54 3.81)
			(end 2.54 3.6703)
			(stroke
				(width 0.1524)
				(type default)
			)
			(layer "F.SilkS")
		)
		(fp_line
			(start 0 3.175)
			(end 0 3.81)
			(stroke
				(width 0.1524)
				(type default)
			)
			(layer "F.SilkS")
		)
		(fp_line
			(start 2.54 1.4097)
			(end 2.54 1.1303)
			(stroke
				(width 0.1524)
				(type default)
			)
			(layer "F.SilkS")
		)
		(fp_line
			(start 0 0.635)
			(end 0 1.905)
			(stroke
				(width 0.1524)
				(type default)
			)
			(layer "F.SilkS")
		)
		(fp_line
			(start 2.54 -1.1303)
			(end 2.54 -1.27)
			(stroke
				(width 0.1524)
				(type default)
			)
			(layer "F.SilkS")
		)
		(fp_line
			(start 0 -1.27)
			(end 0 -0.635)
			(stroke
				(width 0.1524)
				(type default)
			)
			(layer "F.SilkS")
		)
		(fp_line
			(start 2.54 -1.27)
			(end 0 -1.27)
			(stroke
				(width 0.1524)
				(type default)
			)
			(layer "F.SilkS")
		)
		(fp_poly
			(pts
				(xy -1.33604 -0.088392) (xy -2.86004 0.673608) (xy -2.86004 -0.850392)
			)
			(stroke
				(width 0)
				(type default)
			)
			(fill yes)
			(layer "F.SilkS")
		)
		(fp_line
			(start 0 3.81)
			(end 2.54 3.81)
			(stroke
				(width 0.1)
				(type default)
			)
			(layer "F.Fab")
		)
		(fp_line
			(start 2.54 3.81)
			(end 2.54 -1.27)
			(stroke
				(width 0.1)
				(type default)
			)
			(layer "F.Fab")
		)
		(fp_line
			(start 0 -1.27)
			(end 0 3.81)
			(stroke
				(width 0.1)
				(type default)
			)
			(layer "F.Fab")
		)
		(fp_line
			(start 2.54 -1.27)
			(end 0 -1.27)
			(stroke
				(width 0.1)
				(type default)
			)
			(layer "F.Fab")
		)
		(fp_poly
			(pts
				(xy -0.761746 0) (xy -2.285746 -0.762) (xy -2.285746 0.762)
			)
			(stroke
				(width 0)
				(type default)
			)
			(fill yes)
			(layer "F.Fab")
		)
		(pad "1" thru_hole circle
			(at 0 0 270)
			(size 1.0033 1.0033)
			(drill 0.249936)
			(layers "*.Cu" "*.Mask")
			(remove_unused_layers no)
			(net "TDR_DIFF_100_IN1_DN")
			(clearance 0.10795)
			(thermal_gap 0.10795)
			(padstack
				(mode front_inner_back)
				(layer "Inner"
					(shape circle)
					(size 0.8001 0.8001)
					(clearance 0.1524)
				)
				(layer "B.Cu"
					(shape circle)
					(size 1.0033 1.0033)
					(clearance 0.10795)
				)
			)
		)
		(pad "2" thru_hole circle
			(at 2.54 0 270)
			(size 1.9939 1.9939)
			(drill 0.249936)
			(layers "*.Cu" "*.Mask")
			(remove_unused_layers no)
			(net "T1_GND")
			(clearance 0.10795)
			(thermal_gap 0.10795)
			(padstack
				(mode front_inner_back)
				(layer "Inner"
					(shape circle)
					(size 0.8001 0.8001)
					(clearance 0.1524)
				)
				(layer "B.Cu"
					(shape circle)
					(size 1.9939 1.9939)
					(clearance 0.10795)
				)
			)
		)
		(pad "3" thru_hole circle
			(at 2.54 2.54 270)
			(size 1.9939 1.9939)
			(drill 0.249936)
			(layers "*.Cu" "*.Mask")
			(remove_unused_layers no)
			(net "T1_GND")
			(clearance 0.10795)
			(thermal_gap 0.10795)
			(padstack
				(mode front_inner_back)
				(layer "Inner"
					(shape circle)
					(size 0.8001 0.8001)
					(clearance 0.1524)
				)
				(layer "B.Cu"
					(shape circle)
					(size 1.9939 1.9939)
					(clearance 0.10795)
				)
			)
		)
		(pad "4" thru_hole circle
			(at 0 2.54 270)
			(size 1.0033 1.0033)
			(drill 0.249936)
			(layers "*.Cu" "*.Mask")
			(remove_unused_layers no)
			(net "TDR_DIFF_100_IN1_DP")
			(clearance 0.10795)
			(thermal_gap 0.10795)
			(padstack
				(mode front_inner_back)
				(layer "Inner"
					(shape circle)
					(size 0.8001 0.8001)
					(clearance 0.1524)
				)
				(layer "B.Cu"
					(shape circle)
					(size 1.0033 1.0033)
					(clearance 0.10795)
				)
			)
		)
	)
	(footprint ""
		(layer "F.Cu")
		(at 306.090574 -426.179742)
		(property "Reference" "R4264"
			(at 0 0 0)
			(layer "F.SilkS")
			(hide yes)
			(effects
				(font
					(size 1.27 1.27)
				)
			)
		)
		(property "Value" ""
			(at 0 0 0)
			(layer "F.Fab")
			(effects
				(font
					(size 1.27 1.27)
				)
			)
		)
		(duplicate_pad_numbers_are_jumpers no)
		(fp_line
			(start -0.7874 -0.4064)
			(end 0.7874 -0.4064)
			(stroke
				(width 0.1524)
				(type default)
			)
			(layer "F.SilkS")
		)
		(fp_line
			(start -0.7874 0.4064)
			(end -0.7874 -0.4064)
			(stroke
				(width 0.1524)
				(type default)
			)
			(layer "F.SilkS")
		)
		(fp_line
			(start 0.7874 -0.4064)
			(end 0.7874 0.4064)
			(stroke
				(width 0.1524)
				(type default)
			)
			(layer "F.SilkS")
		)
		(fp_line
			(start 0.7874 0.4064)
			(end -0.7874 0.4064)
			(stroke
				(width 0.1524)
				(type default)
			)
			(layer "F.SilkS")
		)
		(fp_line
			(start -0.67945 -0.305054)
			(end -0.12065 -0.305054)
			(stroke
				(width 0.1)
				(type default)
			)
			(layer "F.Fab")
		)
		(fp_line
			(start -0.67945 0.3048)
			(end -0.67945 -0.305054)
			(stroke
				(width 0.1)
				(type default)
			)
			(layer "F.Fab")
		)
		(fp_line
			(start -0.12065 -0.305054)
			(end -0.12065 -0.2794)
			(stroke
				(width 0.1)
				(type default)
			)
			(layer "F.Fab")
		)
		(fp_line
			(start -0.12065 -0.2794)
			(end 0.12065 -0.2794)
			(stroke
				(width 0.1)
				(type default)
			)
			(layer "F.Fab")
		)
		(fp_line
			(start -0.12065 0.2794)
			(end -0.12065 0.3048)
			(stroke
				(width 0.1)
				(type default)
			)
			(layer "F.Fab")
		)
		(fp_line
			(start -0.12065 0.3048)
			(end -0.67945 0.3048)
			(stroke
				(width 0.1)
				(type default)
			)
			(layer "F.Fab")
		)
		(fp_line
			(start 0.120396 0.2794)
			(end -0.12065 0.2794)
			(stroke
				(width 0.1)
				(type default)
			)
			(layer "F.Fab")
		)
		(fp_line
			(start 0.120396 0.3048)
			(end 0.120396 0.2794)
			(stroke
				(width 0.1)
				(type default)
			)
			(layer "F.Fab")
		)
		(fp_line
			(start 0.12065 -0.3048)
			(end 0.67945 -0.3048)
			(stroke
				(width 0.1)
				(type default)
			)
			(layer "F.Fab")
		)
		(fp_line
			(start 0.12065 -0.2794)
			(end 0.12065 -0.3048)
			(stroke
				(width 0.1)
				(type default)
			)
			(layer "F.Fab")
		)
		(fp_line
			(start 0.67945 -0.3048)
			(end 0.67945 0.3048)
			(stroke
				(width 0.1)
				(type default)
			)
			(layer "F.Fab")
		)
		(fp_line
			(start 0.67945 0.3048)
			(end 0.120396 0.3048)
			(stroke
				(width 0.1)
				(type default)
			)
			(layer "F.Fab")
		)
		(pad "1" smd circle
			(at -0.40005 0)
			(size 0 0)
			(layers "F.Cu" "F.Mask" "F.Paste")
			(net "P3V3_AUX")
		)
		(pad "2" smd circle
			(at 0.40005 0)
			(size 0 0)
			(layers "F.Cu" "F.Mask" "F.Paste")
			(net "PWRGD_P3V3_AUX_PDB_BUF_R")
		)
	)
)
